(kicad_pcb
	(version 20260206)
	(generator "pcbnew")
	(generator_version "10.0")
	(general
		(thickness 1.6)
		(legacy_teardrops no)
	)
	(paper "A4")
	(title_block
		(title "04192023_DAF0TMB3IC0_F0TG_MB_C_brd_V02_OCP.brd")
		(comment 1 "Grand Teton / footprints 1657-1662 of 8354")
	)
	(layers
		(0 "F.Cu" signal "TOP")
		(4 "In1.Cu" signal "GND")
		(6 "In2.Cu" signal "IN1")
		(8 "In3.Cu" signal "GND1")
		(10 "In4.Cu" signal "IN2")
		(12 "In5.Cu" signal "GND2")
		(14 "In6.Cu" signal "IN3")
		(16 "In7.Cu" signal "GND3")
		(18 "In8.Cu" signal "VCC")
		(20 "In9.Cu" signal "VCC1")
		(22 "In10.Cu" signal "GND4")
		(24 "In11.Cu" signal "IN4")
		(26 "In12.Cu" signal "GND5")
		(28 "In13.Cu" signal "IN5")
		(30 "In14.Cu" signal "GND6")
		(32 "In15.Cu" signal "IN6")
		(34 "In16.Cu" signal "GND7")
		(2 "B.Cu" signal "BOTTOM")
		(9 "F.Adhes" user "F.Adhesive")
		(11 "B.Adhes" user "B.Adhesive")
		(13 "F.Paste" user "Package Geometry/Pastemask Top")
		(15 "B.Paste" user "Package Geometry/Pastemask Bottom")
		(5 "F.SilkS" user "Ref Des/Silkscreen Top")
		(7 "B.SilkS" user "Ref Des/Silkscreen Bottom")
		(1 "F.Mask" user "Board Geometry/Soldermask Top")
		(3 "B.Mask" user "Board Geometry/Soldermask Bottom")
		(17 "Dwgs.User" user "User.Drawings")
		(19 "Cmts.User" user "User.Comments")
		(21 "Eco1.User" user "User.Eco1")
		(23 "Eco2.User" user "User.Eco2")
		(25 "Edge.Cuts" user "Board Geometry/Outline")
		(27 "Margin" user)
		(31 "F.CrtYd" user "Package Geometry/Place Bound Top")
		(29 "B.CrtYd" user "Package Geometry/Place Bound Bottom")
		(35 "F.Fab" user "Ref Des/Assembly Top")
		(33 "B.Fab" user "Ref Des/Assembly Bottom")
	)
	(footprint ""
		(layer "F.Cu")
		(at 323.024246 -333.253842 90)
		(property "Reference" "PR507"
			(at 0 0 90)
			(layer "F.SilkS")
			(hide yes)
			(effects
				(font
					(size 1.27 1.27)
				)
			)
		)
		(property "Value" ""
			(at 0 0 90)
			(layer "F.Fab")
			(effects
				(font
					(size 1.27 1.27)
				)
			)
		)
		(duplicate_pad_numbers_are_jumpers no)
		(fp_line
			(start 0.7874 -0.4064)
			(end 0.7874 0.4064)
			(stroke
				(width 0.1524)
				(type default)
			)
			(layer "F.SilkS")
		)
		(fp_line
			(start -0.7874 -0.4064)
			(end 0.7874 -0.4064)
			(stroke
				(width 0.1524)
				(type default)
			)
			(layer "F.SilkS")
		)
		(fp_line
			(start 0.7874 0.4064)
			(end -0.7874 0.4064)
			(stroke
				(width 0.1524)
				(type default)
			)
			(layer "F.SilkS")
		)
		(fp_line
			(start -0.7874 0.4064)
			(end -0.7874 -0.4064)
			(stroke
				(width 0.1524)
				(type default)
			)
			(layer "F.SilkS")
		)
		(fp_line
			(start -0.12065 -0.305054)
			(end -0.12065 -0.2794)
			(stroke
				(width 0.1)
				(type default)
			)
			(layer "F.Fab")
		)
		(fp_line
			(start -0.67945 -0.305054)
			(end -0.12065 -0.305054)
			(stroke
				(width 0.1)
				(type default)
			)
			(layer "F.Fab")
		)
		(fp_line
			(start 0.67945 -0.3048)
			(end 0.67945 0.3048)
			(stroke
				(width 0.1)
				(type default)
			)
			(layer "F.Fab")
		)
		(fp_line
			(start 0.12065 -0.3048)
			(end 0.67945 -0.3048)
			(stroke
				(width 0.1)
				(type default)
			)
			(layer "F.Fab")
		)
		(fp_line
			(start 0.12065 -0.2794)
			(end 0.12065 -0.3048)
			(stroke
				(width 0.1)
				(type default)
			)
			(layer "F.Fab")
		)
		(fp_line
			(start -0.12065 -0.2794)
			(end 0.12065 -0.2794)
			(stroke
				(width 0.1)
				(type default)
			)
			(layer "F.Fab")
		)
		(fp_line
			(start 0.120396 0.2794)
			(end -0.12065 0.2794)
			(stroke
				(width 0.1)
				(type default)
			)
			(layer "F.Fab")
		)
		(fp_line
			(start -0.12065 0.2794)
			(end -0.12065 0.3048)
			(stroke
				(width 0.1)
				(type default)
			)
			(layer "F.Fab")
		)
		(fp_line
			(start 0.67945 0.3048)
			(end 0.120396 0.3048)
			(stroke
				(width 0.1)
				(type default)
			)
			(layer "F.Fab")
		)
		(fp_line
			(start 0.120396 0.3048)
			(end 0.120396 0.2794)
			(stroke
				(width 0.1)
				(type default)
			)
			(layer "F.Fab")
		)
		(fp_line
			(start -0.12065 0.3048)
			(end -0.67945 0.3048)
			(stroke
				(width 0.1)
				(type default)
			)
			(layer "F.Fab")
		)
		(fp_line
			(start -0.67945 0.3048)
			(end -0.67945 -0.305054)
			(stroke
				(width 0.1)
				(type default)
			)
			(layer "F.Fab")
		)
		(pad "1" smd circle
			(at -0.40005 0 90)
			(size 0 0)
			(layers "F.Cu" "F.Mask" "F.Paste")
			(net "SW_PVDDCR_CPU1_P0_SW2_RC")
		)
		(pad "2" smd circle
			(at 0.40005 0 90)
			(size 0 0)
			(layers "F.Cu" "F.Mask" "F.Paste")
			(net "GND")
		)
	)
	(footprint ""
		(layer "F.Cu")
		(at 153.543 -107.061 180)
		(property "Reference" "U23"
			(at -1.447292 2.35839 0)
			(unlocked yes)
			(layer "F.SilkS")
			(effects
				(font
					(size 0.7874 0.5842)
					(thickness 0.1524)
				)
				(justify left)
			)
		)
		(property "Value" ""
			(at 0 0 180)
			(layer "F.Fab")
			(effects
				(font
					(size 1.27 1.27)
				)
			)
		)
		(duplicate_pad_numbers_are_jumpers no)
		(fp_line
			(start 1.733296 1.549908)
			(end 1.733296 -1.549908)
			(stroke
				(width 0.1524)
				(type default)
			)
			(layer "F.SilkS")
		)
		(fp_line
			(start 1.733296 -1.549908)
			(end 0.660908 -1.549908)
			(stroke
				(width 0.1524)
				(type default)
			)
			(layer "F.SilkS")
		)
		(fp_line
			(start 0.660908 -1.549908)
			(end 0 -0.889)
			(stroke
				(width 0.1524)
				(type default)
			)
			(layer "F.SilkS")
		)
		(fp_line
			(start 0 -0.889)
			(end -0.660908 -1.549908)
			(stroke
				(width 0.1524)
				(type default)
			)
			(layer "F.SilkS")
		)
		(fp_line
			(start -0.660908 -1.549908)
			(end -1.733296 -1.549908)
			(stroke
				(width 0.1524)
				(type default)
			)
			(layer "F.SilkS")
		)
		(fp_line
			(start -1.733296 1.549908)
			(end 1.733296 1.549908)
			(stroke
				(width 0.1524)
				(type default)
			)
			(layer "F.SilkS")
		)
		(fp_line
			(start -1.733296 -1.549908)
			(end -1.733296 1.549908)
			(stroke
				(width 0.1524)
				(type default)
			)
			(layer "F.SilkS")
		)
		(fp_poly
			(pts
				(xy -2.17297 -2.058162) (xy -2.488692 -1.660144) (xy -1.932686 -1.543558)
			)
			(stroke
				(width 0)
				(type default)
			)
			(fill yes)
			(layer "F.SilkS")
		)
		(fp_line
			(start 0.849884 1.549908)
			(end 0.849884 -1.549908)
			(stroke
				(width 0.1)
				(type default)
			)
			(layer "F.Fab")
		)
		(fp_line
			(start 0.849884 -1.549908)
			(end -0.849884 -1.549908)
			(stroke
				(width 0.1)
				(type default)
			)
			(layer "F.Fab")
		)
		(fp_line
			(start -0.849884 1.549908)
			(end 0.849884 1.549908)
			(stroke
				(width 0.1)
				(type default)
			)
			(layer "F.Fab")
		)
		(fp_line
			(start -0.849884 -1.549908)
			(end -0.849884 1.549908)
			(stroke
				(width 0.1)
				(type default)
			)
			(layer "F.Fab")
		)
		(fp_poly
			(pts
				(xy -2.4384 -1.20396) (xy -2.4384 -0.69596) (xy -1.9304 -0.94996)
			)
			(stroke
				(width 0)
				(type default)
			)
			(fill yes)
			(layer "F.Fab")
		)
		(pad "1" smd rect
			(at -1.199896 -0.94996 90)
			(size 0.5588 0.8128)
			(layers "F.Cu" "F.Mask" "F.Paste")
			(net "P12V_OCP_SFF_EN_R3")
		)
		(pad "2" smd rect
			(at -1.199896 0 90)
			(size 0.5588 0.8128)
			(layers "F.Cu" "F.Mask" "F.Paste")
			(net "HP_LVC3_OCP_SFF_PRSNT2")
		)
		(pad "3" smd rect
			(at -1.199896 0.94996 90)
			(size 0.5588 0.8128)
			(layers "F.Cu" "F.Mask" "F.Paste")
			(net "GND")
		)
		(pad "4" smd rect
			(at 1.199896 0.94996 90)
			(size 0.5588 0.8128)
			(layers "F.Cu" "F.Mask" "F.Paste")
			(net "P12V_OCP_SFF_BUF_EN")
		)
		(pad "5" smd rect
			(at 1.199896 -0.94996 90)
			(size 0.5588 0.8128)
			(layers "F.Cu" "F.Mask" "F.Paste")
			(net "P3V3_AUX")
		)
	)
	(footprint ""
		(layer "F.Cu")
		(at 200.600564 -68.026788)
		(property "Reference" "PC2203"
			(at 0 0 0)
			(layer "F.SilkS")
			(hide yes)
			(effects
				(font
					(size 1.27 1.27)
				)
			)
		)
		(property "Value" ""
			(at 0 0 0)
			(layer "F.Fab")
			(effects
				(font
					(size 1.27 1.27)
				)
			)
		)
		(duplicate_pad_numbers_are_jumpers no)
		(fp_line
			(start -0.7874 -0.4064)
			(end 0.7874 -0.4064)
			(stroke
				(width 0.1524)
				(type default)
			)
			(layer "F.SilkS")
		)
		(fp_line
			(start -0.7874 0.4064)
			(end -0.7874 -0.4064)
			(stroke
				(width 0.1524)
				(type default)
			)
			(layer "F.SilkS")
		)
		(fp_line
			(start 0.7874 -0.4064)
			(end 0.7874 0.4064)
			(stroke
				(width 0.1524)
				(type default)
			)
			(layer "F.SilkS")
		)
		(fp_line
			(start 0.7874 0.4064)
			(end -0.7874 0.4064)
			(stroke
				(width 0.1524)
				(type default)
			)
			(layer "F.SilkS")
		)
		(fp_line
			(start -0.67945 -0.305054)
			(end -0.12065 -0.305054)
			(stroke
				(width 0.1)
				(type default)
			)
			(layer "F.Fab")
		)
		(fp_line
			(start -0.67945 0.3048)
			(end -0.67945 -0.305054)
			(stroke
				(width 0.1)
				(type default)
			)
			(layer "F.Fab")
		)
		(fp_line
			(start -0.12065 -0.305054)
			(end -0.12065 -0.2794)
			(stroke
				(width 0.1)
				(type default)
			)
			(layer "F.Fab")
		)
		(fp_line
			(start -0.12065 -0.2794)
			(end 0.12065 -0.2794)
			(stroke
				(width 0.1)
				(type default)
			)
			(layer "F.Fab")
		)
		(fp_line
			(start -0.12065 0.2794)
			(end -0.12065 0.3048)
			(stroke
				(width 0.1)
				(type default)
			)
			(layer "F.Fab")
		)
		(fp_line
			(start -0.12065 0.3048)
			(end -0.67945 0.3048)
			(stroke
				(width 0.1)
				(type default)
			)
			(layer "F.Fab")
		)
		(fp_line
			(start 0.120396 0.2794)
			(end -0.12065 0.2794)
			(stroke
				(width 0.1)
				(type default)
			)
			(layer "F.Fab")
		)
		(fp_line
			(start 0.120396 0.3048)
			(end 0.120396 0.2794)
			(stroke
				(width 0.1)
				(type default)
			)
			(layer "F.Fab")
		)
		(fp_line
			(start 0.12065 -0.3048)
			(end 0.67945 -0.3048)
			(stroke
				(width 0.1)
				(type default)
			)
			(layer "F.Fab")
		)
		(fp_line
			(start 0.12065 -0.2794)
			(end 0.12065 -0.3048)
			(stroke
				(width 0.1)
				(type default)
			)
			(layer "F.Fab")
		)
		(fp_line
			(start 0.67945 -0.3048)
			(end 0.67945 0.3048)
			(stroke
				(width 0.1)
				(type default)
			)
			(layer "F.Fab")
		)
		(fp_line
			(start 0.67945 0.3048)
			(end 0.120396 0.3048)
			(stroke
				(width 0.1)
				(type default)
			)
			(layer "F.Fab")
		)
		(pad "1" smd circle
			(at -0.40005 0)
			(size 0 0)
			(layers "F.Cu" "F.Mask" "F.Paste")
			(net "P3V3_E1S_GATE_0_PU293")
		)
		(pad "2" smd circle
			(at 0.40005 0)
			(size 0 0)
			(layers "F.Cu" "F.Mask" "F.Paste")
			(net "GND")
		)
	)
	(footprint ""
		(layer "F.Cu")
		(at 445.157098 -92.468192 180)
		(property "Reference" "R3628"
			(at 0 0 180)
			(layer "F.SilkS")
			(hide yes)
			(effects
				(font
					(size 1.27 1.27)
				)
			)
		)
		(property "Value" ""
			(at 0 0 180)
			(layer "F.Fab")
			(effects
				(font
					(size 1.27 1.27)
				)
			)
		)
		(duplicate_pad_numbers_are_jumpers no)
		(fp_line
			(start 0.7874 0.4064)
			(end -0.7874 0.4064)
			(stroke
				(width 0.1524)
				(type default)
			)
			(layer "F.SilkS")
		)
		(fp_line
			(start 0.7874 -0.4064)
			(end 0.7874 0.4064)
			(stroke
				(width 0.1524)
				(type default)
			)
			(layer "F.SilkS")
		)
		(fp_line
			(start -0.7874 0.4064)
			(end -0.7874 -0.4064)
			(stroke
				(width 0.1524)
				(type default)
			)
			(layer "F.SilkS")
		)
		(fp_line
			(start -0.7874 -0.4064)
			(end 0.7874 -0.4064)
			(stroke
				(width 0.1524)
				(type default)
			)
			(layer "F.SilkS")
		)
		(fp_line
			(start 0.67945 0.3048)
			(end 0.120396 0.3048)
			(stroke
				(width 0.1)
				(type default)
			)
			(layer "F.Fab")
		)
		(fp_line
			(start 0.67945 -0.3048)
			(end 0.67945 0.3048)
			(stroke
				(width 0.1)
				(type default)
			)
			(layer "F.Fab")
		)
		(fp_line
			(start 0.12065 -0.2794)
			(end 0.12065 -0.3048)
			(stroke
				(width 0.1)
				(type default)
			)
			(layer "F.Fab")
		)
		(fp_line
			(start 0.12065 -0.3048)
			(end 0.67945 -0.3048)
			(stroke
				(width 0.1)
				(type default)
			)
			(layer "F.Fab")
		)
		(fp_line
			(start 0.120396 0.3048)
			(end 0.120396 0.2794)
			(stroke
				(width 0.1)
				(type default)
			)
			(layer "F.Fab")
		)
		(fp_line
			(start 0.120396 0.2794)
			(end -0.12065 0.2794)
			(stroke
				(width 0.1)
				(type default)
			)
			(layer "F.Fab")
		)
		(fp_line
			(start -0.12065 0.3048)
			(end -0.67945 0.3048)
			(stroke
				(width 0.1)
				(type default)
			)
			(layer "F.Fab")
		)
		(fp_line
			(start -0.12065 0.2794)
			(end -0.12065 0.3048)
			(stroke
				(width 0.1)
				(type default)
			)
			(layer "F.Fab")
		)
		(fp_line
			(start -0.12065 -0.2794)
			(end 0.12065 -0.2794)
			(stroke
				(width 0.1)
				(type default)
			)
			(layer "F.Fab")
		)
		(fp_line
			(start -0.12065 -0.305054)
			(end -0.12065 -0.2794)
			(stroke
				(width 0.1)
				(type default)
			)
			(layer "F.Fab")
		)
		(fp_line
			(start -0.67945 0.3048)
			(end -0.67945 -0.305054)
			(stroke
				(width 0.1)
				(type default)
			)
			(layer "F.Fab")
		)
		(fp_line
			(start -0.67945 -0.305054)
			(end -0.12065 -0.305054)
			(stroke
				(width 0.1)
				(type default)
			)
			(layer "F.Fab")
		)
		(pad "1" smd circle
			(at -0.40005 0 180)
			(size 0 0)
			(layers "F.Cu" "F.Mask" "F.Paste")
			(net "P3V3_AUX")
		)
		(pad "2" smd circle
			(at 0.40005 0 180)
			(size 0 0)
			(layers "F.Cu" "F.Mask" "F.Paste")
			(net "INA230_1_A1")
		)
	)
	(footprint ""
		(layer "F.Cu")
		(at 176.79162 -413.836358 90)
		(property "Reference" "R2923"
			(at 0 0 90)
			(layer "F.SilkS")
			(hide yes)
			(effects
				(font
					(size 1.27 1.27)
				)
			)
		)
		(property "Value" ""
			(at 0 0 90)
			(layer "F.Fab")
			(effects
				(font
					(size 1.27 1.27)
				)
			)
		)
		(duplicate_pad_numbers_are_jumpers no)
		(fp_line
			(start 0.7874 -0.4064)
			(end 0.7874 0.4064)
			(stroke
				(width 0.1524)
				(type default)
			)
			(layer "F.SilkS")
		)
		(fp_line
			(start -0.7874 -0.4064)
			(end 0.7874 -0.4064)
			(stroke
				(width 0.1524)
				(type default)
			)
			(layer "F.SilkS")
		)
		(fp_line
			(start 0.7874 0.4064)
			(end -0.7874 0.4064)
			(stroke
				(width 0.1524)
				(type default)
			)
			(layer "F.SilkS")
		)
		(fp_line
			(start -0.7874 0.4064)
			(end -0.7874 -0.4064)
			(stroke
				(width 0.1524)
				(type default)
			)
			(layer "F.SilkS")
		)
		(fp_line
			(start -0.12065 -0.305054)
			(end -0.12065 -0.2794)
			(stroke
				(width 0.1)
				(type default)
			)
			(layer "F.Fab")
		)
		(fp_line
			(start -0.67945 -0.305054)
			(end -0.12065 -0.305054)
			(stroke
				(width 0.1)
				(type default)
			)
			(layer "F.Fab")
		)
		(fp_line
			(start 0.67945 -0.3048)
			(end 0.67945 0.3048)
			(stroke
				(width 0.1)
				(type default)
			)
			(layer "F.Fab")
		)
		(fp_line
			(start 0.12065 -0.3048)
			(end 0.67945 -0.3048)
			(stroke
				(width 0.1)
				(type default)
			)
			(layer "F.Fab")
		)
		(fp_line
			(start 0.12065 -0.2794)
			(end 0.12065 -0.3048)
			(stroke
				(width 0.1)
				(type default)
			)
			(layer "F.Fab")
		)
		(fp_line
			(start -0.12065 -0.2794)
			(end 0.12065 -0.2794)
			(stroke
				(width 0.1)
				(type default)
			)
			(layer "F.Fab")
		)
		(fp_line
			(start 0.120396 0.2794)
			(end -0.12065 0.2794)
			(stroke
				(width 0.1)
				(type default)
			)
			(layer "F.Fab")
		)
		(fp_line
			(start -0.12065 0.2794)
			(end -0.12065 0.3048)
			(stroke
				(width 0.1)
				(type default)
			)
			(layer "F.Fab")
		)
		(fp_line
			(start 0.67945 0.3048)
			(end 0.120396 0.3048)
			(stroke
				(width 0.1)
				(type default)
			)
			(layer "F.Fab")
		)
		(fp_line
			(start 0.120396 0.3048)
			(end 0.120396 0.2794)
			(stroke
				(width 0.1)
				(type default)
			)
			(layer "F.Fab")
		)
		(fp_line
			(start -0.12065 0.3048)
			(end -0.67945 0.3048)
			(stroke
				(width 0.1)
				(type default)
			)
			(layer "F.Fab")
		)
		(fp_line
			(start -0.67945 0.3048)
			(end -0.67945 -0.305054)
			(stroke
				(width 0.1)
				(type default)
			)
			(layer "F.Fab")
		)
		(pad "1" smd circle
			(at -0.40005 0 90)
			(size 0 0)
			(layers "F.Cu" "F.Mask" "F.Paste")
			(net "P3V3_AUX")
		)
		(pad "2" smd circle
			(at 0.40005 0 90)
			(size 0 0)
			(layers "F.Cu" "F.Mask" "F.Paste")
			(net "PU_U181_INT")
		)
	)
	(footprint ""
		(layer "F.Cu")
		(at 137.762488 -385.09448 180)
		(property "Reference" "L33"
			(at 0 0 180)
			(layer "F.SilkS")
			(hide yes)
			(effects
				(font
					(size 1.27 1.27)
				)
			)
		)
		(property "Value" ""
			(at 0 0 180)
			(layer "F.Fab")
			(effects
				(font
					(size 1.27 1.27)
				)
			)
		)
		(duplicate_pad_numbers_are_jumpers no)
		(fp_line
			(start 0.762 0.381)
			(end -0.762 0.381)
			(stroke
				(width 0.1524)
				(type default)
			)
			(layer "F.SilkS")
		)
		(fp_line
			(start 0.762 -0.381)
			(end 0.762 0.381)
			(stroke
				(width 0.1524)
				(type default)
			)
			(layer "F.SilkS")
		)
		(fp_line
			(start -0.762 0.381)
			(end -0.762 -0.381)
			(stroke
				(width 0.1524)
				(type default)
			)
			(layer "F.SilkS")
		)
		(fp_line
			(start -0.762 -0.381)
			(end 0.762 -0.381)
			(stroke
				(width 0.1524)
				(type default)
			)
			(layer "F.SilkS")
		)
		(fp_line
			(start 0.680466 0.306324)
			(end 0.118364 0.306324)
			(stroke
				(width 0.1)
				(type default)
			)
			(layer "F.Fab")
		)
		(fp_line
			(start 0.680466 -0.306324)
			(end 0.680466 0.306324)
			(stroke
				(width 0.1)
				(type default)
			)
			(layer "F.Fab")
		)
		(fp_line
			(start 0.118872 -0.2794)
			(end 0.118872 -0.306324)
			(stroke
				(width 0.1)
				(type default)
			)
			(layer "F.Fab")
		)
		(fp_line
			(start 0.118872 -0.306324)
			(end 0.680466 -0.306324)
			(stroke
				(width 0.1)
				(type default)
			)
			(layer "F.Fab")
		)
		(fp_line
			(start 0.118364 0.306324)
			(end 0.118364 0.2794)
			(stroke
				(width 0.1)
				(type default)
			)
			(layer "F.Fab")
		)
		(fp_line
			(start 0.118364 0.2794)
			(end -0.119634 0.2794)
			(stroke
				(width 0.1)
				(type default)
			)
			(layer "F.Fab")
		)
		(fp_line
			(start -0.118364 -0.2794)
			(end 0.118872 -0.2794)
			(stroke
				(width 0.1)
				(type default)
			)
			(layer "F.Fab")
		)
		(fp_line
			(start -0.118364 -0.307086)
			(end -0.118364 -0.2794)
			(stroke
				(width 0.1)
				(type default)
			)
			(layer "F.Fab")
		)
		(fp_line
			(start -0.119634 0.30607)
			(end -0.681736 0.30607)
			(stroke
				(width 0.1)
				(type default)
			)
			(layer "F.Fab")
		)
		(fp_line
			(start -0.119634 0.2794)
			(end -0.119634 0.30607)
			(stroke
				(width 0.1)
				(type default)
			)
			(layer "F.Fab")
		)
		(fp_line
			(start -0.681736 0.30607)
			(end -0.681736 -0.307086)
			(stroke
				(width 0.1)
				(type default)
			)
			(layer "F.Fab")
		)
		(fp_line
			(start -0.681736 -0.307086)
			(end -0.118364 -0.307086)
			(stroke
				(width 0.1)
				(type default)
			)
			(layer "F.Fab")
		)
		(pad "1" smd rect
			(at -0.40005 0)
			(size 0.4572 0.508)
			(layers "F.Cu" "F.Mask" "F.Paste")
			(net "P1V8_CPU1_RT_1D")
		)
		(pad "2" smd rect
			(at 0.40005 0)
			(size 0.4572 0.508)
			(layers "F.Cu" "F.Mask" "F.Paste")
			(net "P1V8_CPU1_RT3_1A_1D")
		)
	)
)
